# BASEBOARD_FAB2 (Tioga Pass) — schematic netlist excerpt (pin names and nets, part order shuffled) for the footprints in the layout excerpt that follows; sources: Cadence DE-HDL packaged netlist, KiCad conversion of Wiwynn_Tioga_Pass_MB.brd

R4D29  RES  27.4 1% CHIP  pkg 0402  page 103 : A = CLK_100M_CPU0_BCLK0_R_DP ; B = CLK_100M_CPU0_BCLK0_DP

(kicad_pcb
	(version 20260206)
	(generator "pcbnew")
	(generator_version "10.0")
	(general
		(thickness 1.6)
		(legacy_teardrops no)
	)
	(paper "A4")
	(title_block
		(title "Wiwynn_Tioga_Pass_MB.brd")
		(comment 1 "Tioga Pass / footprints 866-866 of 4770")
	)
	(layers
		(0 "F.Cu" signal "TOP")
		(4 "In1.Cu" signal "L2GND")
		(6 "In2.Cu" signal "L3")
		(8 "In3.Cu" signal "L4GND")
		(10 "In4.Cu" signal "L5")
		(12 "In5.Cu" signal "L6GND")
		(14 "In6.Cu" signal "L7VCC")
		(16 "In7.Cu" signal "L8VCC")
		(18 "In8.Cu" signal "L9GND")
		(20 "In9.Cu" signal "L10")
		(22 "In10.Cu" signal "L11GND")
		(24 "In11.Cu" signal "L12")
		(26 "In12.Cu" signal "L13GND")
		(2 "B.Cu" signal "BOTTOM")
		(9 "F.Adhes" user "F.Adhesive")
		(11 "B.Adhes" user "B.Adhesive")
		(13 "F.Paste" user "Package Geometry/Pastemask Top")
		(15 "B.Paste" user "Package Geometry/Pastemask Bottom")
		(5 "F.SilkS" user "Ref Des/Silkscreen Top")
		(7 "B.SilkS" user "Ref Des/Silkscreen Bottom")
		(1 "F.Mask" user "Board Geometry/Soldermask Top")
		(3 "B.Mask" user "Board Geometry/Soldermask Bottom")
		(17 "Dwgs.User" user "User.Drawings")
		(19 "Cmts.User" user "User.Comments")
		(21 "Eco1.User" user "User.Eco1")
		(23 "Eco2.User" user "User.Eco2")
		(25 "Edge.Cuts" user "Board Geometry/Outline")
		(27 "Margin" user)
		(31 "F.CrtYd" user "Package Geometry/Place Bound Top")
		(29 "B.CrtYd" user "Package Geometry/Place Bound Bottom")
		(35 "F.Fab" user "Ref Des/Assembly Top")
		(33 "B.Fab" user "Ref Des/Assembly Bottom")
	)
	(footprint ""
		(layer "F.Cu")
		(at 175.387 -76.327 90)
		(property "Reference" "R4D29"
			(at 0 0 90)
			(layer "F.SilkS")
			(hide yes)
			(effects
				(font
					(size 1.27 1.27)
				)
			)
		)
		(property "Value" ""
			(at 0 0 90)
			(layer "F.Fab")
			(effects
				(font
					(size 1.27 1.27)
				)
			)
		)
		(duplicate_pad_numbers_are_jumpers no)
		(fp_poly
			(pts
				(xy -0.2794 -0.1016) (xy 0.2794 -0.1016) (xy 0.2794 0.9906) (xy -0.2794 0.9906)
			)
			(stroke
				(width 0)
				(type default)
			)
			(fill no)
			(layer "F.CrtYd")
		)
		(fp_line
			(start 0.2794 -0.1016)
			(end -0.2794 -0.1016)
			(stroke
				(width 0.1)
				(type default)
			)
			(layer "F.Fab")
		)
		(fp_line
			(start -0.2794 -0.1016)
			(end -0.2794 0.9906)
			(stroke
				(width 0.1)
				(type default)
			)
			(layer "F.Fab")
		)
		(fp_line
			(start 0.2794 0.9906)
			(end 0.2794 -0.1016)
			(stroke
				(width 0.1)
				(type default)
			)
			(layer "F.Fab")
		)
		(fp_line
			(start -0.2794 0.9906)
			(end 0.2794 0.9906)
			(stroke
				(width 0.1)
				(type default)
			)
			(layer "F.Fab")
		)
		(pad "1" smd rect
			(at 0 0 90)
			(size 0.508 0.508)
			(layers "F.Cu" "F.Mask" "F.Paste")
			(net "CLK_100M_CPU0_BCLK0_R_DP")
		)
		(pad "2" smd rect
			(at 0 0.889 90)
			(size 0.508 0.508)
			(layers "F.Cu" "F.Mask" "F.Paste")
			(net "CLK_100M_CPU0_BCLK0_DP")
		)
		(zone
			(layer "F.Cu")
			(hatch none 0.5)
			(connect_pads
				(clearance 0)
			)
			(min_thickness 0.25)
			(keepout
				(tracks allowed)
				(vias not_allowed)
				(pads allowed)
				(copperpour not_allowed)
				(footprints allowed)
			)
			(placement
				(enabled no)
				(sheetname "")
			)
			(fill
				(thermal_gap 0.5)
				(thermal_bridge_width 0.5)
				(island_removal_mode 0)
			)
			(polygon
				(pts
					(xy 175.641 -76.073) (xy 175.641 -76.581) (xy 176.022 -76.581) (xy 176.022 -76.073)
				)
			)
		)
		(zone
			(layer "F.Cu")
			(hatch none 0.5)
			(connect_pads
				(clearance 0)
			)
			(min_thickness 0.25)
			(keepout
				(tracks not_allowed)
				(vias allowed)
				(pads allowed)
				(copperpour not_allowed)
				(footprints allowed)
			)
			(placement
				(enabled no)
				(sheetname "")
			)
			(fill
				(thermal_gap 0.5)
				(thermal_bridge_width 0.5)
				(island_removal_mode 0)
			)
			(polygon
				(pts
					(xy 176.022 -76.073) (xy 176.022 -76.581) (xy 175.641 -76.581) (xy 175.641 -76.073)
				)
			)
		)
	)
)
